FILE_TYPE = CONNECTIVITY;
{Allegro Design Entry HDL 16.6-p007 (v16-6-112F) 10/10/2012}
"PAGE_NUMBER" = 252;
0"NC";
END.
